# SA800U (Snapdragon 845) Baseboard — symbol library table
(sym_lib_table
  (lib (name "sa800u-baseboard-hw")(type "KiCad")(uri "${KIPRJMOD}/lib/sa800u-baseboard-hw.kicad_sym")(options "")(descr ""))
)
